(kicad_pcb
	(version 20260206)
	(generator "pcbnew")
	(generator_version "10.0")
	(general
		(thickness 1.6)
		(legacy_teardrops no)
	)
	(paper "A4")
	(title_block
		(title "Bryce Canyon_IOM_M2_16342-2_OCP.brd")
		(comment 1 "Bryce Canyon / footprints 435-440 of 1146")
	)
	(layers
		(0 "F.Cu" signal "TOP")
		(4 "In1.Cu" signal "L2GND")
		(6 "In2.Cu" signal "L3")
		(8 "In3.Cu" signal "L4VCC")
		(10 "In4.Cu" signal "L5VCC")
		(12 "In5.Cu" signal "L6")
		(14 "In6.Cu" signal "L7GND")
		(2 "B.Cu" signal "BOTTOM")
		(9 "F.Adhes" user "F.Adhesive")
		(11 "B.Adhes" user "B.Adhesive")
		(13 "F.Paste" user "Package Geometry/Pastemask Top")
		(15 "B.Paste" user "Package Geometry/Pastemask Bottom")
		(5 "F.SilkS" user "Ref Des/Silkscreen Top")
		(7 "B.SilkS" user "Ref Des/Silkscreen Bottom")
		(1 "F.Mask" user "Board Geometry/Soldermask Top")
		(3 "B.Mask" user "Board Geometry/Soldermask Bottom")
		(17 "Dwgs.User" user "User.Drawings")
		(19 "Cmts.User" user "User.Comments")
		(21 "Eco1.User" user "User.Eco1")
		(23 "Eco2.User" user "User.Eco2")
		(25 "Edge.Cuts" user "Board Geometry/Outline")
		(27 "Margin" user)
		(31 "F.CrtYd" user "Package Geometry/Place Bound Top")
		(29 "B.CrtYd" user "Package Geometry/Place Bound Bottom")
		(35 "F.Fab" user "Ref Des/Assembly Top")
		(33 "B.Fab" user "Ref Des/Assembly Bottom")
	)
	(footprint ""
		(layer "F.Cu")
		(at 93.177106 -142.653766 -90)
		(property "Reference" "U34"
			(at 0 0 270)
			(layer "F.SilkS")
			(hide yes)
			(effects
				(font
					(size 1.27 1.27)
				)
			)
		)
		(property "Value" "TCA9555PWR-GP"
			(at 0 -6.9342 270)
			(unlocked yes)
			(layer "F.Fab")
			(hide yes)
			(effects
				(font
					(size 1.016 1.016)
					(thickness 0.1524)
				)
			)
		)
		(property "Device Type" "TSOIC24H48"
			(at 0 -8.5852 270)
			(unlocked yes)
			(layer "F.Fab")
			(hide yes)
			(effects
				(font
					(size 1.016 1.016)
					(thickness 0.1524)
				)
			)
		)
		(duplicate_pad_numbers_are_jumpers no)
		(fp_line
			(start -4.2291 3.937)
			(end -4.2291 -1.397)
			(stroke
				(width 0.1524)
				(type default)
			)
			(layer "F.SilkS")
		)
		(fp_line
			(start -4.22656 3.81)
			(end -4.2291 1.397)
			(stroke
				(width 0.508)
				(type default)
			)
			(layer "F.SilkS")
		)
		(fp_line
			(start 3.81 1.397)
			(end -4.2291 1.397)
			(stroke
				(width 0.1524)
				(type default)
			)
			(layer "F.SilkS")
		)
		(fp_line
			(start -3.429 0)
			(end -4.2291 0.8001)
			(stroke
				(width 0.1524)
				(type default)
			)
			(layer "F.SilkS")
		)
		(fp_line
			(start -4.2291 -0.8001)
			(end -3.429 0)
			(stroke
				(width 0.1524)
				(type default)
			)
			(layer "F.SilkS")
		)
		(fp_line
			(start -4.2291 -1.397)
			(end 3.81 -1.397)
			(stroke
				(width 0.1524)
				(type default)
			)
			(layer "F.SilkS")
		)
		(fp_line
			(start 3.81 -1.397)
			(end 3.81 1.397)
			(stroke
				(width 0.1524)
				(type default)
			)
			(layer "F.SilkS")
		)
		(fp_poly
			(pts
				(xy -3.90652 -1.8542) (xy 3.90652 -1.8542) (xy 3.90652 1.8542) (xy -3.90652 1.8542)
			)
			(stroke
				(width 0)
				(type default)
			)
			(fill yes)
			(layer "F.SilkS")
		)
		(fp_poly
			(pts
				(xy -4.2164 3.81) (xy 4.2164 3.81) (xy 4.22656 -3.81) (xy -4.2164 -3.81)
			)
			(stroke
				(width 0)
				(type default)
			)
			(fill no)
			(layer "F.CrtYd")
		)
		(fp_poly
			(pts
				(xy -4.22656 -3.81) (xy 4.22656 -3.81) (xy 4.22656 3.81) (xy -4.22656 3.81)
			)
			(stroke
				(width 0)
				(type default)
			)
			(fill no)
			(layer "F.Fab")
		)
		(pad "1" smd rect
			(at -3.57632 2.8194 270)
			(size 0.3556 1.524)
			(layers "F.Cu" "F.Mask" "F.Paste")
			(net "IO_EXP0_RESET#_FLT")
		)
		(pad "2" smd rect
			(at -2.92608 2.8194 270)
			(size 0.3556 1.524)
			(layers "F.Cu" "F.Mask" "F.Paste")
			(net "TCA9555_A1")
		)
		(pad "3" smd rect
			(at -2.27584 2.8194 270)
			(size 0.3556 1.524)
			(layers "F.Cu" "F.Mask" "F.Paste")
			(net "TCA9555_A2")
		)
		(pad "4" smd rect
			(at -1.6256 2.8194 270)
			(size 0.3556 1.524)
			(layers "F.Cu" "F.Mask" "F.Paste")
			(net "LED_POSTCODE_0")
		)
		(pad "5" smd rect
			(at -0.97536 2.8194 270)
			(size 0.3556 1.524)
			(layers "F.Cu" "F.Mask" "F.Paste")
			(net "LED_POSTCODE_1")
		)
		(pad "6" smd rect
			(at -0.32512 2.8194 270)
			(size 0.3556 1.524)
			(layers "F.Cu" "F.Mask" "F.Paste")
			(net "LED_POSTCODE_2")
		)
		(pad "7" smd rect
			(at 0.32512 2.8194 270)
			(size 0.3556 1.524)
			(layers "F.Cu" "F.Mask" "F.Paste")
			(net "LED_POSTCODE_3")
		)
		(pad "8" smd rect
			(at 0.97536 2.8194 270)
			(size 0.3556 1.524)
			(layers "F.Cu" "F.Mask" "F.Paste")
			(net "LED_POSTCODE_4")
		)
		(pad "9" smd rect
			(at 1.6256 2.8194 270)
			(size 0.3556 1.524)
			(layers "F.Cu" "F.Mask" "F.Paste")
			(net "LED_POSTCODE_5")
		)
		(pad "10" smd rect
			(at 2.27584 2.8194 270)
			(size 0.3556 1.524)
			(layers "F.Cu" "F.Mask" "F.Paste")
			(net "LED_POSTCODE_6")
		)
		(pad "11" smd rect
			(at 2.92608 2.8194 270)
			(size 0.3556 1.524)
			(layers "F.Cu" "F.Mask" "F.Paste")
			(net "LED_POSTCODE_7")
		)
		(pad "12" smd rect
			(at 3.57632 2.8194 270)
			(size 0.3556 1.524)
			(layers "F.Cu" "F.Mask" "F.Paste")
			(net "GND")
		)
		(pad "13" smd rect
			(at 3.57632 -2.8194 270)
			(size 0.3556 1.524)
			(layers "F.Cu" "F.Mask" "F.Paste")
			(net "DEBUG_RST_BTN_N")
		)
		(pad "14" smd rect
			(at 2.92608 -2.8194 270)
			(size 0.3556 1.524)
			(layers "F.Cu" "F.Mask" "F.Paste")
			(net "DEBUG_GPIO_BMC_1")
		)
		(pad "15" smd rect
			(at 2.27584 -2.8194 270)
			(size 0.3556 1.524)
			(layers "F.Cu" "F.Mask" "F.Paste")
			(net "DEBUG_GPIO_BMC_2")
		)
		(pad "16" smd rect
			(at 1.6256 -2.8194 270)
			(size 0.3556 1.524)
			(layers "F.Cu" "F.Mask" "F.Paste")
			(net "DEBUG_GPIO_BMC_3")
		)
		(pad "17" smd rect
			(at 0.97536 -2.8194 270)
			(size 0.3556 1.524)
			(layers "F.Cu" "F.Mask" "F.Paste")
			(net "DEBUG_GPIO_BMC_4")
		)
		(pad "18" smd rect
			(at 0.32512 -2.8194 270)
			(size 0.3556 1.524)
			(layers "F.Cu" "F.Mask" "F.Paste")
			(net "DEBUG_GPIO_BMC_5")
		)
		(pad "19" smd rect
			(at -0.32512 -2.8194 270)
			(size 0.3556 1.524)
			(layers "F.Cu" "F.Mask" "F.Paste")
			(net "DEBUG_GPIO_BMC_6")
		)
		(pad "20" smd rect
			(at -0.97536 -2.8194 270)
			(size 0.3556 1.524)
			(layers "F.Cu" "F.Mask" "F.Paste")
			(net "DEBUG_HDR_UART_SEL")
		)
		(pad "21" smd rect
			(at -1.6256 -2.8194 270)
			(size 0.3556 1.524)
			(layers "F.Cu" "F.Mask" "F.Paste")
			(net "TCA9555_A0")
		)
		(pad "22" smd rect
			(at -2.27584 -2.8194 270)
			(size 0.3556 1.524)
			(layers "F.Cu" "F.Mask" "F.Paste")
			(net "I2C_DEBUG_SCL_R")
		)
		(pad "23" smd rect
			(at -2.92608 -2.8194 270)
			(size 0.3556 1.524)
			(layers "F.Cu" "F.Mask" "F.Paste")
			(net "I2C_DEBUG_SDA_R")
		)
		(pad "24" smd rect
			(at -3.57632 -2.8194 270)
			(size 0.3556 1.524)
			(layers "F.Cu" "F.Mask" "F.Paste")
			(net "P3V3_STBY")
		)
	)
	(footprint ""
		(layer "F.Cu")
		(at 98.425 -135.4836 90)
		(property "Reference" "R139"
			(at 0 0 90)
			(layer "F.SilkS")
			(hide yes)
			(effects
				(font
					(size 1.27 1.27)
				)
			)
		)
		(property "Value" "8K2R2J-3-GP"
			(at 0.064008 -3.993896 90)
			(unlocked yes)
			(layer "F.Fab")
			(hide yes)
			(effects
				(font
					(size 1.016 1.016)
					(thickness 0.1524)
				)
			)
		)
		(property "Device Type" "R402H16"
			(at 0.064008 -5.517896 90)
			(unlocked yes)
			(layer "F.Fab")
			(hide yes)
			(effects
				(font
					(size 1.016 1.016)
					(thickness 0.1524)
				)
			)
		)
		(duplicate_pad_numbers_are_jumpers no)
		(fp_line
			(start 0.508 -0.9398)
			(end -0.508 -0.9398)
			(stroke
				(width 0.1524)
				(type default)
			)
			(layer "F.SilkS")
		)
		(fp_line
			(start -0.508 -0.9398)
			(end -0.508 0.9398)
			(stroke
				(width 0.1524)
				(type default)
			)
			(layer "F.SilkS")
		)
		(fp_rect
			(start -0.508 0.9398)
			(end 0.508 -0.9398)
			(stroke
				(width 0)
				(type default)
			)
			(fill no)
			(layer "F.CrtYd")
		)
		(fp_rect
			(start -0.508 0.9398)
			(end 0.508 -0.9398)
			(stroke
				(width 0)
				(type default)
			)
			(fill no)
			(layer "F.Fab")
		)
		(pad "1" smd custom
			(at 0 -0.4445 90)
			(size 0.1397 0.1397)
			(layers "F.Cu" "F.Mask" "F.Paste")
			(net "EEPROM_WP")
			(options
				(clearance outline)
				(anchor circle)
			)
			(primitives
				(gr_poly
					(pts
						(arc
							(start -0.1778 -0.2794)
							(mid -0.249642 -0.249642)
							(end -0.2794 -0.1778)
						)
						(arc
							(start -0.2794 0.1778)
							(mid -0.249642 0.249642)
							(end -0.1778 0.2794)
						)
						(arc
							(start 0.1778 0.2794)
							(mid 0.249642 0.249642)
							(end 0.2794 0.1778)
						)
						(arc
							(start 0.2794 -0.1778)
							(mid 0.249642 -0.249642)
							(end 0.1778 -0.2794)
						)
					)
					(width 0)
					(fill yes)
				)
			)
		)
		(pad "2" smd custom
			(at 0 0.4445 90)
			(size 0.1397 0.1397)
			(layers "F.Cu" "F.Mask" "F.Paste")
			(net "GND")
			(options
				(clearance outline)
				(anchor circle)
			)
			(primitives
				(gr_poly
					(pts
						(arc
							(start -0.1778 -0.2794)
							(mid -0.249642 -0.249642)
							(end -0.2794 -0.1778)
						)
						(arc
							(start -0.2794 0.1778)
							(mid -0.249642 0.249642)
							(end -0.1778 0.2794)
						)
						(arc
							(start 0.1778 0.2794)
							(mid 0.249642 0.249642)
							(end 0.2794 0.1778)
						)
						(arc
							(start 0.2794 -0.1778)
							(mid 0.249642 -0.249642)
							(end 0.1778 -0.2794)
						)
					)
					(width 0)
					(fill yes)
				)
			)
		)
	)
	(footprint ""
		(layer "F.Cu")
		(at 8.904732 -138.145774 90)
		(property "Reference" "R229"
			(at 0 0 90)
			(layer "F.SilkS")
			(hide yes)
			(effects
				(font
					(size 1.27 1.27)
				)
			)
		)
		(property "Value" "120R2F-GP"
			(at 0.064008 -3.993896 90)
			(unlocked yes)
			(layer "F.Fab")
			(hide yes)
			(effects
				(font
					(size 1.016 1.016)
					(thickness 0.1524)
				)
			)
		)
		(property "Device Type" "R402H16"
			(at 0.064008 -5.517896 90)
			(unlocked yes)
			(layer "F.Fab")
			(hide yes)
			(effects
				(font
					(size 1.016 1.016)
					(thickness 0.1524)
				)
			)
		)
		(duplicate_pad_numbers_are_jumpers no)
		(fp_line
			(start 0.508 -0.9398)
			(end -0.508 -0.9398)
			(stroke
				(width 0.1524)
				(type default)
			)
			(layer "F.SilkS")
		)
		(fp_line
			(start -0.508 -0.9398)
			(end -0.508 0.9398)
			(stroke
				(width 0.1524)
				(type default)
			)
			(layer "F.SilkS")
		)
		(fp_rect
			(start -0.508 0.9398)
			(end 0.508 -0.9398)
			(stroke
				(width 0)
				(type default)
			)
			(fill no)
			(layer "F.CrtYd")
		)
		(fp_rect
			(start -0.508 0.9398)
			(end 0.508 -0.9398)
			(stroke
				(width 0)
				(type default)
			)
			(fill no)
			(layer "F.Fab")
		)
		(pad "1" smd custom
			(at 0 -0.4445 90)
			(size 0.1397 0.1397)
			(layers "F.Cu" "F.Mask" "F.Paste")
			(net "GND")
			(options
				(clearance outline)
				(anchor circle)
			)
			(primitives
				(gr_poly
					(pts
						(arc
							(start -0.1778 -0.2794)
							(mid -0.249642 -0.249642)
							(end -0.2794 -0.1778)
						)
						(arc
							(start -0.2794 0.1778)
							(mid -0.249642 0.249642)
							(end -0.1778 0.2794)
						)
						(arc
							(start 0.1778 0.2794)
							(mid 0.249642 0.249642)
							(end 0.2794 0.1778)
						)
						(arc
							(start 0.2794 -0.1778)
							(mid 0.249642 -0.249642)
							(end 0.1778 -0.2794)
						)
					)
					(width 0)
					(fill yes)
				)
			)
		)
		(pad "2" smd custom
			(at 0 0.4445 90)
			(size 0.1397 0.1397)
			(layers "F.Cu" "F.Mask" "F.Paste")
			(net "MEMBA_0")
			(options
				(clearance outline)
				(anchor circle)
			)
			(primitives
				(gr_poly
					(pts
						(arc
							(start -0.1778 -0.2794)
							(mid -0.249642 -0.249642)
							(end -0.2794 -0.1778)
						)
						(arc
							(start -0.2794 0.1778)
							(mid -0.249642 0.249642)
							(end -0.1778 0.2794)
						)
						(arc
							(start 0.1778 0.2794)
							(mid 0.249642 0.249642)
							(end 0.2794 0.1778)
						)
						(arc
							(start 0.2794 -0.1778)
							(mid 0.249642 -0.249642)
							(end 0.1778 -0.2794)
						)
					)
					(width 0)
					(fill yes)
				)
			)
		)
	)
	(footprint ""
		(layer "F.Cu")
		(at 68.5038 -119.4562 -90)
		(property "Reference" "R266"
			(at 0 0 270)
			(layer "F.SilkS")
			(hide yes)
			(effects
				(font
					(size 1.27 1.27)
				)
			)
		)
		(property "Value" "2K2R2J-2-GP"
			(at 0.064008 -3.993896 270)
			(unlocked yes)
			(layer "F.Fab")
			(hide yes)
			(effects
				(font
					(size 1.016 1.016)
					(thickness 0.1524)
				)
			)
		)
		(property "Device Type" "R402H16"
			(at 0.064008 -5.517896 270)
			(unlocked yes)
			(layer "F.Fab")
			(hide yes)
			(effects
				(font
					(size 1.016 1.016)
					(thickness 0.1524)
				)
			)
		)
		(duplicate_pad_numbers_are_jumpers no)
		(fp_line
			(start -0.508 -0.9398)
			(end -0.508 0.9398)
			(stroke
				(width 0.1524)
				(type default)
			)
			(layer "F.SilkS")
		)
		(fp_line
			(start 0.508 -0.9398)
			(end -0.508 -0.9398)
			(stroke
				(width 0.1524)
				(type default)
			)
			(layer "F.SilkS")
		)
		(fp_rect
			(start -0.508 0.9398)
			(end 0.508 -0.9398)
			(stroke
				(width 0)
				(type default)
			)
			(fill no)
			(layer "F.CrtYd")
		)
		(fp_rect
			(start -0.508 0.9398)
			(end 0.508 -0.9398)
			(stroke
				(width 0)
				(type default)
			)
			(fill no)
			(layer "F.Fab")
		)
		(pad "1" smd custom
			(at 0 -0.4445 270)
			(size 0.1397 0.1397)
			(layers "F.Cu" "F.Mask" "F.Paste")
			(net "P3V3_STBY")
			(options
				(clearance outline)
				(anchor circle)
			)
			(primitives
				(gr_poly
					(pts
						(arc
							(start -0.1778 -0.2794)
							(mid -0.249642 -0.249642)
							(end -0.2794 -0.1778)
						)
						(arc
							(start -0.2794 0.1778)
							(mid -0.249642 0.249642)
							(end -0.1778 0.2794)
						)
						(arc
							(start 0.1778 0.2794)
							(mid 0.249642 0.249642)
							(end 0.2794 0.1778)
						)
						(arc
							(start 0.2794 -0.1778)
							(mid 0.249642 -0.249642)
							(end 0.1778 -0.2794)
						)
					)
					(width 0)
					(fill yes)
				)
			)
		)
		(pad "2" smd custom
			(at 0 0.4445 270)
			(size 0.1397 0.1397)
			(layers "F.Cu" "F.Mask" "F.Paste")
			(net "FLA1_SPI_RST")
			(options
				(clearance outline)
				(anchor circle)
			)
			(primitives
				(gr_poly
					(pts
						(arc
							(start -0.1778 -0.2794)
							(mid -0.249642 -0.249642)
							(end -0.2794 -0.1778)
						)
						(arc
							(start -0.2794 0.1778)
							(mid -0.249642 0.249642)
							(end -0.1778 0.2794)
						)
						(arc
							(start 0.1778 0.2794)
							(mid 0.249642 0.249642)
							(end 0.2794 0.1778)
						)
						(arc
							(start 0.2794 -0.1778)
							(mid 0.249642 -0.249642)
							(end 0.1778 -0.2794)
						)
					)
					(width 0)
					(fill yes)
				)
			)
		)
	)
	(footprint ""
		(layer "F.Cu")
		(at 31.75 -152.146 90)
		(property "Reference" "R701"
			(at 0 0 90)
			(layer "F.SilkS")
			(hide yes)
			(effects
				(font
					(size 1.27 1.27)
				)
			)
		)
		(property "Value" "4K7R2F-GP"
			(at 0.064008 -3.993896 90)
			(unlocked yes)
			(layer "F.Fab")
			(hide yes)
			(effects
				(font
					(size 1.016 1.016)
					(thickness 0.1524)
				)
			)
		)
		(property "Device Type" "R402H16"
			(at 0.064008 -5.517896 90)
			(unlocked yes)
			(layer "F.Fab")
			(hide yes)
			(effects
				(font
					(size 1.016 1.016)
					(thickness 0.1524)
				)
			)
		)
		(duplicate_pad_numbers_are_jumpers no)
		(fp_line
			(start 0.508 -0.9398)
			(end -0.508 -0.9398)
			(stroke
				(width 0.1524)
				(type default)
			)
			(layer "F.SilkS")
		)
		(fp_line
			(start -0.508 -0.9398)
			(end -0.508 0.9398)
			(stroke
				(width 0.1524)
				(type default)
			)
			(layer "F.SilkS")
		)
		(fp_rect
			(start -0.508 0.9398)
			(end 0.508 -0.9398)
			(stroke
				(width 0)
				(type default)
			)
			(fill no)
			(layer "F.CrtYd")
		)
		(fp_rect
			(start -0.508 0.9398)
			(end 0.508 -0.9398)
			(stroke
				(width 0)
				(type default)
			)
			(fill no)
			(layer "F.Fab")
		)
		(pad "1" smd custom
			(at 0 -0.4445 90)
			(size 0.1397 0.1397)
			(layers "F.Cu" "F.Mask" "F.Paste")
			(net "P3V3_STBY")
			(options
				(clearance outline)
				(anchor circle)
			)
			(primitives
				(gr_poly
					(pts
						(arc
							(start -0.1778 -0.2794)
							(mid -0.249642 -0.249642)
							(end -0.2794 -0.1778)
						)
						(arc
							(start -0.2794 0.1778)
							(mid -0.249642 0.249642)
							(end -0.1778 0.2794)
						)
						(arc
							(start 0.1778 0.2794)
							(mid 0.249642 0.249642)
							(end 0.2794 0.1778)
						)
						(arc
							(start 0.2794 -0.1778)
							(mid 0.249642 -0.249642)
							(end 0.1778 -0.2794)
						)
					)
					(width 0)
					(fill yes)
				)
			)
		)
		(pad "2" smd custom
			(at 0 0.4445 90)
			(size 0.1397 0.1397)
			(layers "F.Cu" "F.Mask" "F.Paste")
			(net "COMP_FAST_THROTTLE_N")
			(options
				(clearance outline)
				(anchor circle)
			)
			(primitives
				(gr_poly
					(pts
						(arc
							(start -0.1778 -0.2794)
							(mid -0.249642 -0.249642)
							(end -0.2794 -0.1778)
						)
						(arc
							(start -0.2794 0.1778)
							(mid -0.249642 0.249642)
							(end -0.1778 0.2794)
						)
						(arc
							(start 0.1778 0.2794)
							(mid 0.249642 0.249642)
							(end 0.2794 0.1778)
						)
						(arc
							(start 0.2794 -0.1778)
							(mid 0.249642 -0.249642)
							(end 0.1778 -0.2794)
						)
					)
					(width 0)
					(fill yes)
				)
			)
		)
	)
	(footprint ""
		(layer "F.Cu")
		(at 112.87379 -6.643878 -90)
		(property "Reference" "R460"
			(at 0 0 270)
			(layer "F.SilkS")
			(hide yes)
			(effects
				(font
					(size 1.27 1.27)
				)
			)
		)
		(property "Value" "0R2J-2-GP"
			(at 0.064008 -3.993896 270)
			(unlocked yes)
			(layer "F.Fab")
			(hide yes)
			(effects
				(font
					(size 1.016 1.016)
					(thickness 0.1524)
				)
			)
		)
		(property "Device Type" "R402H16"
			(at 0.064008 -5.517896 270)
			(unlocked yes)
			(layer "F.Fab")
			(hide yes)
			(effects
				(font
					(size 1.016 1.016)
					(thickness 0.1524)
				)
			)
		)
		(duplicate_pad_numbers_are_jumpers no)
		(fp_line
			(start -0.508 -0.9398)
			(end -0.508 0.9398)
			(stroke
				(width 0.1524)
				(type default)
			)
			(layer "F.SilkS")
		)
		(fp_line
			(start 0.508 -0.9398)
			(end -0.508 -0.9398)
			(stroke
				(width 0.1524)
				(type default)
			)
			(layer "F.SilkS")
		)
		(fp_rect
			(start -0.508 0.9398)
			(end 0.508 -0.9398)
			(stroke
				(width 0)
				(type default)
			)
			(fill no)
			(layer "F.CrtYd")
		)
		(fp_rect
			(start -0.508 0.9398)
			(end 0.508 -0.9398)
			(stroke
				(width 0)
				(type default)
			)
			(fill no)
			(layer "F.Fab")
		)
		(pad "1" smd custom
			(at 0 -0.4445 270)
			(size 0.1397 0.1397)
			(layers "F.Cu" "F.Mask" "F.Paste")
			(net "MB0_CM_ADR2_R")
			(options
				(clearance outline)
				(anchor circle)
			)
			(primitives
				(gr_poly
					(pts
						(arc
							(start -0.1778 -0.2794)
							(mid -0.249642 -0.249642)
							(end -0.2794 -0.1778)
						)
						(arc
							(start -0.2794 0.1778)
							(mid -0.249642 0.249642)
							(end -0.1778 0.2794)
						)
						(arc
							(start 0.1778 0.2794)
							(mid 0.249642 0.249642)
							(end 0.2794 0.1778)
						)
						(arc
							(start 0.2794 -0.1778)
							(mid 0.249642 -0.249642)
							(end 0.1778 -0.2794)
						)
					)
					(width 0)
					(fill yes)
				)
			)
		)
		(pad "2" smd custom
			(at 0 0.4445 270)
			(size 0.1397 0.1397)
			(layers "F.Cu" "F.Mask" "F.Paste")
			(net "AGND_CURRENT_MON")
			(options
				(clearance outline)
				(anchor circle)
			)
			(primitives
				(gr_poly
					(pts
						(arc
							(start -0.1778 -0.2794)
							(mid -0.249642 -0.249642)
							(end -0.2794 -0.1778)
						)
						(arc
							(start -0.2794 0.1778)
							(mid -0.249642 0.249642)
							(end -0.1778 0.2794)
						)
						(arc
							(start 0.1778 0.2794)
							(mid 0.249642 0.249642)
							(end 0.2794 0.1778)
						)
						(arc
							(start 0.2794 -0.1778)
							(mid 0.249642 -0.249642)
							(end 0.1778 -0.2794)
						)
					)
					(width 0)
					(fill yes)
				)
			)
		)
	)
)
